#ISCELL
  mstr_symbols bom_note *
  *
#ISCELL
  mstr_symbols intel_corp_bpage *
  *
#ISCELL
  mstr_standard offpage *
  page85_i1
#ISCELL
  mstr_standard tap *
  page85_i10
#ISCELL
  mstr_standard tap *
  page85_i100
#ISCELL
  mstr_standard tap *
  page85_i101
#ISCELL
  mstr_standard tap *
  page85_i102
#ISCELL
  mstr_standard tap *
  page85_i103
#ISCELL
  mstr_standard tap *
  page85_i104
#ISCELL
  mstr_standard tap *
  page85_i105
#ISCELL
  mstr_standard tap *
  page85_i106
#ISCELL
  mstr_standard tap *
  page85_i107
#ISCELL
  mstr_standard tap *
  page85_i108
#ISCELL
  mstr_standard tap *
  page85_i109
#ISCELL
  mstr_standard tap *
  page85_i11
#ISCELL
  mstr_standard tap *
  page85_i110
#CELL
  mstr_sconn sconn288_h44441004 *
  page85_i111
#ISCELL
  mstr_standard tap *
  page85_i112
#ISCELL
  mstr_standard tap *
  page85_i113
#ISCELL
  mstr_standard tap *
  page85_i114
#ISCELL
  mstr_standard tap *
  page85_i115
#ISCELL
  mstr_standard tap *
  page85_i116
#ISCELL
  mstr_standard tap *
  page85_i117
#ISCELL
  mstr_standard tap *
  page85_i118
#ISCELL
  mstr_standard tap *
  page85_i119
#ISCELL
  mstr_standard tap *
  page85_i12
#ISCELL
  mstr_standard tap *
  page85_i120
#ISCELL
  mstr_standard tap *
  page85_i121
#ISCELL
  mstr_standard tap *
  page85_i122
#ISCELL
  mstr_standard tap *
  page85_i123
#ISCELL
  mstr_standard tap *
  page85_i124
#ISCELL
  mstr_standard tap *
  page85_i125
#ISCELL
  mstr_standard tap *
  page85_i126
#ISCELL
  mstr_standard tap *
  page85_i127
#ISCELL
  mstr_standard tap *
  page85_i128
#ISCELL
  mstr_standard tap *
  page85_i129
#ISCELL
  mstr_standard tap *
  page85_i13
#ISCELL
  mstr_standard tap *
  page85_i130
#ISCELL
  mstr_standard offpage *
  page85_i131
#ISCELL
  mstr_standard offpage *
  page85_i132
#ISCELL
  mstr_standard tap *
  page85_i133
#ISCELL
  mstr_standard tap *
  page85_i134
#ISCELL
  mstr_standard tap *
  page85_i135
#ISCELL
  mstr_standard offpage *
  page85_i136
#ISCELL
  mstr_standard offpage *
  page85_i137
#ISCELL
  mstr_standard tap *
  page85_i138
#ISCELL
  mstr_standard tap *
  page85_i139
#ISCELL
  mstr_standard tap *
  page85_i14
#ISCELL
  mstr_standard tap *
  page85_i140
#ISCELL
  mstr_standard tap *
  page85_i141
#ISCELL
  mstr_standard tap *
  page85_i142
#ISCELL
  mstr_standard tap *
  page85_i143
#ISCELL
  mstr_standard tap *
  page85_i144
#ISCELL
  mstr_standard tap *
  page85_i145
#ISCELL
  mstr_standard offpage *
  page85_i146
#ISCELL
  mstr_standard offpage *
  page85_i147
#ISCELL
  mstr_standard offpage *
  page85_i148
#ISCELL
  mstr_standard offpage *
  page85_i149
#ISCELL
  mstr_standard tap *
  page85_i15
#ISCELL
  mstr_standard offpage *
  page85_i150
#ISCELL
  mstr_standard tap *
  page85_i152
#ISCELL
  mstr_standard tap *
  page85_i153
#ISCELL
  mstr_standard tap *
  page85_i154
#ISCELL
  mstr_standard tap *
  page85_i155
#ISCELL
  mstr_standard offpage *
  page85_i156
#ISCELL
  mstr_standard offpage *
  page85_i157
#ISCELL
  mstr_standard tap *
  page85_i159
#ISCELL
  mstr_symbols pvddq_klm *
  page85_i16
#ISCELL
  mstr_standard tap *
  page85_i160
#ISCELL
  mstr_standard tap *
  page85_i161
#ISCELL
  mstr_standard tap *
  page85_i162
#ISCELL
  mstr_standard tap *
  page85_i163
#ISCELL
  mstr_standard offpage *
  page85_i164
#ISCELL
  mstr_standard offpage *
  page85_i165
#ISCELL
  mstr_standard tap *
  page85_i166
#ISCELL
  mstr_standard tap *
  page85_i167
#ISCELL
  mstr_standard tap *
  page85_i168
#ISCELL
  mstr_standard offpage *
  page85_i169
#ISCELL
  mstr_symbols pvtt_klm *
  page85_i17
#CELL
  mstr_sconn sconn288_h44441004 *
  page85_i172
#ISCELL
  mstr_symbols gnd *
  page85_i173
#ISCELL
  mstr_symbols gnd *
  page85_i175
#ISCELL
  mstr_standard offpage *
  page85_i176
#ISCELL
  mstr_standard offpage *
  page85_i177
#ISCELL
  mstr_standard offpage *
  page85_i178
#ISCELL
  mstr_standard offpage *
  page85_i179
#ISCELL
  mstr_symbols gnd *
  page85_i180
#CELL
  dev_discrete cap_a *
  page85_i181
#ISCELL
  mstr_symbols pvpp_klm *
  page85_i182
#ISCELL
  mstr_symbols pvpp_klm *
  page85_i183
#ISCELL
  mstr_standard offpage *
  page85_i184
#ISCELL
  mstr_symbols p12v_nvdimm_klm *
  page85_i185
#ISCELL
  mstr_standard tap *
  page85_i19
#ISCELL
  mstr_standard offpage *
  page85_i2
#ISCELL
  mstr_standard tap *
  page85_i20
#ISCELL
  mstr_standard tap *
  page85_i21
#ISCELL
  mstr_standard tap *
  page85_i22
#ISCELL
  mstr_standard tap *
  page85_i23
#ISCELL
  mstr_standard tap *
  page85_i24
#ISCELL
  mstr_standard tap *
  page85_i25
#ISCELL
  mstr_standard tap *
  page85_i26
#ISCELL
  mstr_standard tap *
  page85_i27
#ISCELL
  mstr_standard tap *
  page85_i28
#ISCELL
  mstr_standard tap *
  page85_i29
#ISCELL
  mstr_standard tap *
  page85_i3
#ISCELL
  mstr_standard tap *
  page85_i30
#ISCELL
  mstr_standard tap *
  page85_i31
#ISCELL
  mstr_standard tap *
  page85_i32
#ISCELL
  mstr_standard tap *
  page85_i33
#ISCELL
  mstr_standard tap *
  page85_i34
#ISCELL
  mstr_standard tap *
  page85_i35
#ISCELL
  mstr_standard tap *
  page85_i36
#ISCELL
  mstr_standard tap *
  page85_i37
#ISCELL
  mstr_standard tap *
  page85_i38
#ISCELL
  mstr_standard tap *
  page85_i39
#ISCELL
  mstr_standard tap *
  page85_i4
#ISCELL
  mstr_standard tap *
  page85_i40
#ISCELL
  mstr_standard tap *
  page85_i41
#CELL
  mstr_sconn sconn288_h44441004 *
  page85_i43
#ISCELL
  mstr_symbols gnd *
  page85_i44
#ISCELL
  mstr_standard offpage *
  page85_i45
#ISCELL
  mstr_standard tap *
  page85_i46
#ISCELL
  mstr_standard tap *
  page85_i47
#ISCELL
  mstr_standard tap *
  page85_i48
#ISCELL
  mstr_standard tap *
  page85_i49
#ISCELL
  mstr_standard tap *
  page85_i5
#ISCELL
  mstr_standard tap *
  page85_i50
#ISCELL
  mstr_standard tap *
  page85_i51
#ISCELL
  mstr_standard tap *
  page85_i52
#ISCELL
  mstr_standard tap *
  page85_i53
#ISCELL
  mstr_standard tap *
  page85_i54
#ISCELL
  mstr_standard tap *
  page85_i55
#ISCELL
  mstr_standard tap *
  page85_i56
#ISCELL
  mstr_standard tap *
  page85_i57
#ISCELL
  mstr_standard tap *
  page85_i58
#ISCELL
  mstr_standard tap *
  page85_i59
#ISCELL
  mstr_standard tap *
  page85_i6
#ISCELL
  mstr_standard tap *
  page85_i60
#ISCELL
  mstr_standard tap *
  page85_i61
#ISCELL
  mstr_standard tap *
  page85_i62
#ISCELL
  mstr_standard tap *
  page85_i63
#ISCELL
  mstr_standard tap *
  page85_i64
#ISCELL
  mstr_standard tap *
  page85_i65
#CELL
  mstr_sconn sconn288_h44441004 *
  page85_i66
#ISCELL
  mstr_standard tap *
  page85_i67
#ISCELL
  mstr_standard tap *
  page85_i68
#ISCELL
  mstr_standard tap *
  page85_i69
#ISCELL
  mstr_standard tap *
  page85_i7
#ISCELL
  mstr_standard tap *
  page85_i70
#ISCELL
  mstr_standard tap *
  page85_i71
#ISCELL
  mstr_standard tap *
  page85_i72
#ISCELL
  mstr_standard tap *
  page85_i73
#ISCELL
  mstr_standard tap *
  page85_i74
#ISCELL
  mstr_standard tap *
  page85_i75
#ISCELL
  mstr_standard tap *
  page85_i76
#ISCELL
  mstr_standard tap *
  page85_i77
#ISCELL
  mstr_standard tap *
  page85_i78
#ISCELL
  mstr_standard tap *
  page85_i79
#ISCELL
  mstr_standard tap *
  page85_i8
#ISCELL
  mstr_standard tap *
  page85_i80
#ISCELL
  mstr_standard tap *
  page85_i81
#ISCELL
  mstr_standard tap *
  page85_i82
#ISCELL
  mstr_standard tap *
  page85_i83
#ISCELL
  mstr_standard tap *
  page85_i84
#ISCELL
  mstr_standard tap *
  page85_i85
#ISCELL
  mstr_standard tap *
  page85_i86
#ISCELL
  mstr_standard tap *
  page85_i87
#ISCELL
  mstr_standard tap *
  page85_i88
#ISCELL
  mstr_standard tap *
  page85_i89
#ISCELL
  mstr_standard tap *
  page85_i9
#ISCELL
  mstr_standard tap *
  page85_i90
#ISCELL
  mstr_standard tap *
  page85_i91
#ISCELL
  mstr_standard tap *
  page85_i92
#ISCELL
  mstr_standard tap *
  page85_i93
#ISCELL
  mstr_standard tap *
  page85_i94
#ISCELL
  mstr_standard tap *
  page85_i95
#ISCELL
  mstr_standard tap *
  page85_i96
#ISCELL
  mstr_standard tap *
  page85_i97
#ISCELL
  mstr_standard tap *
  page85_i98
#ISCELL
  mstr_standard tap *
  page85_i99
